(kicad_pcb
	(version 20260206)
	(generator "pcbnew")
	(generator_version "10.0")
	(general
		(thickness 1.6)
		(legacy_teardrops no)
	)
	(paper "A4")
	(title_block
		(title "Wiwynn_Tioga_Pass_MB.brd")
		(comment 1 "Tioga Pass / footprints 790-795 of 4770")
	)
	(layers
		(0 "F.Cu" signal "TOP")
		(4 "In1.Cu" signal "L2GND")
		(6 "In2.Cu" signal "L3")
		(8 "In3.Cu" signal "L4GND")
		(10 "In4.Cu" signal "L5")
		(12 "In5.Cu" signal "L6GND")
		(14 "In6.Cu" signal "L7VCC")
		(16 "In7.Cu" signal "L8VCC")
		(18 "In8.Cu" signal "L9GND")
		(20 "In9.Cu" signal "L10")
		(22 "In10.Cu" signal "L11GND")
		(24 "In11.Cu" signal "L12")
		(26 "In12.Cu" signal "L13GND")
		(2 "B.Cu" signal "BOTTOM")
		(9 "F.Adhes" user "F.Adhesive")
		(11 "B.Adhes" user "B.Adhesive")
		(13 "F.Paste" user "Package Geometry/Pastemask Top")
		(15 "B.Paste" user "Package Geometry/Pastemask Bottom")
		(5 "F.SilkS" user "Ref Des/Silkscreen Top")
		(7 "B.SilkS" user "Ref Des/Silkscreen Bottom")
		(1 "F.Mask" user "Board Geometry/Soldermask Top")
		(3 "B.Mask" user "Board Geometry/Soldermask Bottom")
		(17 "Dwgs.User" user "User.Drawings")
		(19 "Cmts.User" user "User.Comments")
		(21 "Eco1.User" user "User.Eco1")
		(23 "Eco2.User" user "User.Eco2")
		(25 "Edge.Cuts" user "Board Geometry/Outline")
		(27 "Margin" user)
		(31 "F.CrtYd" user "Package Geometry/Place Bound Top")
		(29 "B.CrtYd" user "Package Geometry/Place Bound Bottom")
		(35 "F.Fab" user "Ref Des/Assembly Top")
		(33 "B.Fab" user "Ref Des/Assembly Bottom")
	)
	(footprint ""
		(layer "F.Cu")
		(at 339.258656 -131.977384)
		(property "Reference" "R7B19"
			(at 1.01473 0.656336 270)
			(unlocked yes)
			(layer "F.SilkS")
			(effects
				(font
					(size 0.4064 0.254)
					(thickness 0.1524)
				)
			)
		)
		(property "Value" ""
			(at 0 0 0)
			(layer "F.Fab")
			(effects
				(font
					(size 1.27 1.27)
				)
			)
		)
		(duplicate_pad_numbers_are_jumpers no)
		(fp_poly
			(pts
				(xy -0.4953 -0.2032) (xy 0.4953 -0.2032) (xy 0.4953 1.6002) (xy -0.4953 1.6002)
			)
			(stroke
				(width 0)
				(type default)
			)
			(fill no)
			(layer "F.CrtYd")
		)
		(fp_line
			(start -0.4953 -0.2032)
			(end 0.4953 -0.2032)
			(stroke
				(width 0.1)
				(type default)
			)
			(layer "F.Fab")
		)
		(fp_line
			(start -0.4953 1.6002)
			(end -0.4953 -0.2032)
			(stroke
				(width 0.1)
				(type default)
			)
			(layer "F.Fab")
		)
		(fp_line
			(start 0.4953 -0.2032)
			(end 0.4953 1.6002)
			(stroke
				(width 0.1)
				(type default)
			)
			(layer "F.Fab")
		)
		(fp_line
			(start 0.4953 1.6002)
			(end -0.4953 1.6002)
			(stroke
				(width 0.1)
				(type default)
			)
			(layer "F.Fab")
		)
		(pad "1" smd rect
			(at 0 0)
			(size 0.762 0.889)
			(layers "F.Cu" "F.Mask" "F.Paste")
			(net "VR_PVPP_DEF_BOOT")
		)
		(pad "2" smd rect
			(at 0 1.397)
			(size 0.762 0.889)
			(layers "F.Cu" "F.Mask" "F.Paste")
			(net "VR_PVPP_DEF_BOOT_R")
		)
		(zone
			(layer "F.Cu")
			(hatch none 0.5)
			(connect_pads
				(clearance 0)
			)
			(min_thickness 0.25)
			(keepout
				(tracks not_allowed)
				(vias allowed)
				(pads allowed)
				(copperpour not_allowed)
				(footprints allowed)
			)
			(placement
				(enabled no)
				(sheetname "")
			)
			(fill
				(thermal_gap 0.5)
				(thermal_bridge_width 0.5)
				(island_removal_mode 0)
			)
			(polygon
				(pts
					(xy 338.877656 -131.024884) (xy 339.639656 -131.024884) (xy 339.639656 -131.532884) (xy 338.877656 -131.532884)
				)
			)
		)
		(zone
			(layer "F.Cu")
			(hatch none 0.5)
			(connect_pads
				(clearance 0)
			)
			(min_thickness 0.25)
			(keepout
				(tracks allowed)
				(vias not_allowed)
				(pads allowed)
				(copperpour not_allowed)
				(footprints allowed)
			)
			(placement
				(enabled no)
				(sheetname "")
			)
			(fill
				(thermal_gap 0.5)
				(thermal_bridge_width 0.5)
				(island_removal_mode 0)
			)
			(polygon
				(pts
					(xy 339.639656 -131.024884) (xy 339.639656 -131.532884) (xy 338.877656 -131.532884) (xy 338.877656 -131.024884)
				)
			)
		)
	)
	(footprint ""
		(layer "F.Cu")
		(at 13.8938 -28.575 90)
		(property "Reference" "C1F13"
			(at 0 0 90)
			(layer "F.SilkS")
			(hide yes)
			(effects
				(font
					(size 1.27 1.27)
				)
			)
		)
		(property "Value" ""
			(at 0 0 90)
			(layer "F.Fab")
			(effects
				(font
					(size 1.27 1.27)
				)
			)
		)
		(duplicate_pad_numbers_are_jumpers no)
		(fp_rect
			(start -0.3048 -0.1016)
			(end 0.3048 0.9906)
			(stroke
				(width 0)
				(type default)
			)
			(fill no)
			(layer "F.CrtYd")
		)
		(fp_line
			(start 0.3048 -0.1016)
			(end -0.3048 -0.1016)
			(stroke
				(width 0.1)
				(type default)
			)
			(layer "F.Fab")
		)
		(fp_line
			(start -0.3048 -0.1016)
			(end -0.3048 0.9906)
			(stroke
				(width 0.1)
				(type default)
			)
			(layer "F.Fab")
		)
		(fp_line
			(start 0.3048 0.9906)
			(end 0.3048 -0.1016)
			(stroke
				(width 0.1)
				(type default)
			)
			(layer "F.Fab")
		)
		(fp_line
			(start -0.3048 0.9906)
			(end 0.3048 0.9906)
			(stroke
				(width 0.1)
				(type default)
			)
			(layer "F.Fab")
		)
		(pad "1" smd rect
			(at 0 0 90)
			(size 0.508 0.508)
			(layers "F.Cu" "F.Mask" "F.Paste")
			(net "P3E_CPU1_PE3_MP_C_TXN<3>")
		)
		(pad "2" smd rect
			(at 0 0.889 90)
			(size 0.508 0.508)
			(layers "F.Cu" "F.Mask" "F.Paste")
			(net "P3E_CPU1_PE3_MP_TXN<3>")
		)
		(zone
			(layer "F.Cu")
			(hatch none 0.5)
			(connect_pads
				(clearance 0)
			)
			(min_thickness 0.25)
			(keepout
				(tracks allowed)
				(vias not_allowed)
				(pads allowed)
				(copperpour not_allowed)
				(footprints allowed)
			)
			(placement
				(enabled no)
				(sheetname "")
			)
			(fill
				(thermal_gap 0.5)
				(thermal_bridge_width 0.5)
				(island_removal_mode 0)
			)
			(polygon
				(pts
					(xy 14.1478 -28.321) (xy 14.5288 -28.321) (xy 14.5288 -28.829) (xy 14.1478 -28.829)
				)
			)
		)
		(zone
			(layer "F.Cu")
			(hatch none 0.5)
			(connect_pads
				(clearance 0)
			)
			(min_thickness 0.25)
			(keepout
				(tracks not_allowed)
				(vias allowed)
				(pads allowed)
				(copperpour not_allowed)
				(footprints allowed)
			)
			(placement
				(enabled no)
				(sheetname "")
			)
			(fill
				(thermal_gap 0.5)
				(thermal_bridge_width 0.5)
				(island_removal_mode 0)
			)
			(polygon
				(pts
					(xy 14.1478 -28.321) (xy 14.5288 -28.321) (xy 14.5288 -28.829) (xy 14.1478 -28.829)
				)
			)
		)
	)
	(footprint ""
		(layer "F.Cu")
		(at 426.5041 -125.6792 -90)
		(property "Reference" "R8B13"
			(at 0 0 270)
			(layer "F.SilkS")
			(hide yes)
			(effects
				(font
					(size 1.27 1.27)
				)
			)
		)
		(property "Value" ""
			(at 0 0 270)
			(layer "F.Fab")
			(effects
				(font
					(size 1.27 1.27)
				)
			)
		)
		(duplicate_pad_numbers_are_jumpers no)
		(fp_poly
			(pts
				(xy -0.2794 -0.1016) (xy 0.2794 -0.1016) (xy 0.2794 0.9906) (xy -0.2794 0.9906)
			)
			(stroke
				(width 0)
				(type default)
			)
			(fill no)
			(layer "F.CrtYd")
		)
		(fp_line
			(start -0.2794 0.9906)
			(end 0.2794 0.9906)
			(stroke
				(width 0.1)
				(type default)
			)
			(layer "F.Fab")
		)
		(fp_line
			(start 0.2794 0.9906)
			(end 0.2794 -0.1016)
			(stroke
				(width 0.1)
				(type default)
			)
			(layer "F.Fab")
		)
		(fp_line
			(start -0.2794 -0.1016)
			(end -0.2794 0.9906)
			(stroke
				(width 0.1)
				(type default)
			)
			(layer "F.Fab")
		)
		(fp_line
			(start 0.2794 -0.1016)
			(end -0.2794 -0.1016)
			(stroke
				(width 0.1)
				(type default)
			)
			(layer "F.Fab")
		)
		(pad "1" smd rect
			(at 0 0 270)
			(size 0.508 0.508)
			(layers "F.Cu" "F.Mask" "F.Paste")
			(net "PVPP_ABC")
		)
		(pad "2" smd rect
			(at 0 0.889 270)
			(size 0.508 0.508)
			(layers "F.Cu" "F.Mask" "F.Paste")
			(net "SMB_HFI1_CPU0_LVC2_SDA")
		)
		(zone
			(layer "F.Cu")
			(hatch none 0.5)
			(connect_pads
				(clearance 0)
			)
			(min_thickness 0.25)
			(keepout
				(tracks not_allowed)
				(vias allowed)
				(pads allowed)
				(copperpour not_allowed)
				(footprints allowed)
			)
			(placement
				(enabled no)
				(sheetname "")
			)
			(fill
				(thermal_gap 0.5)
				(thermal_bridge_width 0.5)
				(island_removal_mode 0)
			)
			(polygon
				(pts
					(xy 425.8691 -125.9332) (xy 425.8691 -125.4252) (xy 426.2501 -125.4252) (xy 426.2501 -125.9332)
				)
			)
		)
		(zone
			(layer "F.Cu")
			(hatch none 0.5)
			(connect_pads
				(clearance 0)
			)
			(min_thickness 0.25)
			(keepout
				(tracks allowed)
				(vias not_allowed)
				(pads allowed)
				(copperpour not_allowed)
				(footprints allowed)
			)
			(placement
				(enabled no)
				(sheetname "")
			)
			(fill
				(thermal_gap 0.5)
				(thermal_bridge_width 0.5)
				(island_removal_mode 0)
			)
			(polygon
				(pts
					(xy 426.2501 -125.9332) (xy 426.2501 -125.4252) (xy 425.8691 -125.4252) (xy 425.8691 -125.9332)
				)
			)
		)
	)
	(footprint ""
		(layer "F.Cu")
		(at 414.8836 -94.7166)
		(property "Reference" "R7W18"
			(at -0.8382 -0.67818 0)
			(unlocked yes)
			(layer "F.SilkS")
			(effects
				(font
					(size 0.4064 0.254)
					(thickness 0.1524)
				)
				(justify left)
			)
		)
		(property "Value" ""
			(at 0 0 0)
			(layer "F.Fab")
			(effects
				(font
					(size 1.27 1.27)
				)
			)
		)
		(duplicate_pad_numbers_are_jumpers no)
		(fp_poly
			(pts
				(xy -0.2794 -0.1016) (xy 0.2794 -0.1016) (xy 0.2794 0.9906) (xy -0.2794 0.9906)
			)
			(stroke
				(width 0)
				(type default)
			)
			(fill no)
			(layer "F.CrtYd")
		)
		(fp_line
			(start -0.2794 -0.1016)
			(end -0.2794 0.9906)
			(stroke
				(width 0.1)
				(type default)
			)
			(layer "F.Fab")
		)
		(fp_line
			(start -0.2794 0.9906)
			(end 0.2794 0.9906)
			(stroke
				(width 0.1)
				(type default)
			)
			(layer "F.Fab")
		)
		(fp_line
			(start 0.2794 -0.1016)
			(end -0.2794 -0.1016)
			(stroke
				(width 0.1)
				(type default)
			)
			(layer "F.Fab")
		)
		(fp_line
			(start 0.2794 0.9906)
			(end 0.2794 -0.1016)
			(stroke
				(width 0.1)
				(type default)
			)
			(layer "F.Fab")
		)
		(pad "1" smd rect
			(at 0 0)
			(size 0.508 0.508)
			(layers "F.Cu" "F.Mask" "F.Paste")
			(net "IRQ_SML1_PMBUS_ALERT_N")
		)
		(pad "2" smd rect
			(at 0 0.889)
			(size 0.508 0.508)
			(layers "F.Cu" "F.Mask" "F.Paste")
			(net "IRQ_SML1_PMBUS_ALERT_R1_N")
		)
		(zone
			(layer "F.Cu")
			(hatch none 0.5)
			(connect_pads
				(clearance 0)
			)
			(min_thickness 0.25)
			(keepout
				(tracks allowed)
				(vias not_allowed)
				(pads allowed)
				(copperpour not_allowed)
				(footprints allowed)
			)
			(placement
				(enabled no)
				(sheetname "")
			)
			(fill
				(thermal_gap 0.5)
				(thermal_bridge_width 0.5)
				(island_removal_mode 0)
			)
			(polygon
				(pts
					(xy 414.6296 -94.4626) (xy 415.1376 -94.4626) (xy 415.1376 -94.0816) (xy 414.6296 -94.0816)
				)
			)
		)
		(zone
			(layer "F.Cu")
			(hatch none 0.5)
			(connect_pads
				(clearance 0)
			)
			(min_thickness 0.25)
			(keepout
				(tracks not_allowed)
				(vias allowed)
				(pads allowed)
				(copperpour not_allowed)
				(footprints allowed)
			)
			(placement
				(enabled no)
				(sheetname "")
			)
			(fill
				(thermal_gap 0.5)
				(thermal_bridge_width 0.5)
				(island_removal_mode 0)
			)
			(polygon
				(pts
					(xy 414.6296 -94.0816) (xy 415.1376 -94.0816) (xy 415.1376 -94.4626) (xy 414.6296 -94.4626)
				)
			)
		)
	)
	(footprint ""
		(layer "F.Cu")
		(at 472.7575 -138.43 90)
		(property "Reference" "R9A21"
			(at 0 0 90)
			(layer "F.SilkS")
			(hide yes)
			(effects
				(font
					(size 1.27 1.27)
				)
			)
		)
		(property "Value" ""
			(at 0 0 90)
			(layer "F.Fab")
			(effects
				(font
					(size 1.27 1.27)
				)
			)
		)
		(duplicate_pad_numbers_are_jumpers no)
		(fp_poly
			(pts
				(xy -0.2794 -0.1016) (xy 0.2794 -0.1016) (xy 0.2794 0.9906) (xy -0.2794 0.9906)
			)
			(stroke
				(width 0)
				(type default)
			)
			(fill no)
			(layer "F.CrtYd")
		)
		(fp_line
			(start 0.2794 -0.1016)
			(end -0.2794 -0.1016)
			(stroke
				(width 0.1)
				(type default)
			)
			(layer "F.Fab")
		)
		(fp_line
			(start -0.2794 -0.1016)
			(end -0.2794 0.9906)
			(stroke
				(width 0.1)
				(type default)
			)
			(layer "F.Fab")
		)
		(fp_line
			(start 0.2794 0.9906)
			(end 0.2794 -0.1016)
			(stroke
				(width 0.1)
				(type default)
			)
			(layer "F.Fab")
		)
		(fp_line
			(start -0.2794 0.9906)
			(end 0.2794 0.9906)
			(stroke
				(width 0.1)
				(type default)
			)
			(layer "F.Fab")
		)
		(pad "1" smd rect
			(at 0 0 90)
			(size 0.508 0.508)
			(layers "F.Cu" "F.Mask" "F.Paste")
			(net "P3V3_STBY")
		)
		(pad "2" smd rect
			(at 0 0.889 90)
			(size 0.508 0.508)
			(layers "F.Cu" "F.Mask" "F.Paste")
			(net "FM_PWR_LED_N")
		)
		(zone
			(layer "F.Cu")
			(hatch none 0.5)
			(connect_pads
				(clearance 0)
			)
			(min_thickness 0.25)
			(keepout
				(tracks allowed)
				(vias not_allowed)
				(pads allowed)
				(copperpour not_allowed)
				(footprints allowed)
			)
			(placement
				(enabled no)
				(sheetname "")
			)
			(fill
				(thermal_gap 0.5)
				(thermal_bridge_width 0.5)
				(island_removal_mode 0)
			)
			(polygon
				(pts
					(xy 473.0115 -138.176) (xy 473.0115 -138.684) (xy 473.3925 -138.684) (xy 473.3925 -138.176)
				)
			)
		)
		(zone
			(layer "F.Cu")
			(hatch none 0.5)
			(connect_pads
				(clearance 0)
			)
			(min_thickness 0.25)
			(keepout
				(tracks not_allowed)
				(vias allowed)
				(pads allowed)
				(copperpour not_allowed)
				(footprints allowed)
			)
			(placement
				(enabled no)
				(sheetname "")
			)
			(fill
				(thermal_gap 0.5)
				(thermal_bridge_width 0.5)
				(island_removal_mode 0)
			)
			(polygon
				(pts
					(xy 473.3925 -138.176) (xy 473.3925 -138.684) (xy 473.0115 -138.684) (xy 473.0115 -138.176)
				)
			)
		)
	)
	(footprint ""
		(layer "F.Cu")
		(at 480.22764 -137.328402 -90)
		(property "Reference" "DS9A5"
			(at -0.9017 3.57505 90)
			(unlocked yes)
			(layer "F.SilkS")
			(effects
				(font
					(size 0.7874 0.5842)
					(thickness 0.1524)
				)
			)
		)
		(property "Value" ""
			(at 0 0 270)
			(layer "F.Fab")
			(effects
				(font
					(size 1.27 1.27)
				)
			)
		)
		(duplicate_pad_numbers_are_jumpers no)
		(fp_line
			(start -0.1016 5.61213)
			(end -0.1016 4.488688)
			(stroke
				(width 0.1524)
				(type default)
			)
			(layer "F.SilkS")
		)
		(fp_line
			(start -0.582422 4.488688)
			(end 0.379222 4.488688)
			(stroke
				(width 0.1524)
				(type default)
			)
			(layer "F.SilkS")
		)
		(fp_line
			(start -0.1016 4.488688)
			(end -0.582422 3.655822)
			(stroke
				(width 0.1524)
				(type default)
			)
			(layer "F.SilkS")
		)
		(fp_line
			(start -0.582422 3.655822)
			(end -0.1016 3.655822)
			(stroke
				(width 0.1524)
				(type default)
			)
			(layer "F.SilkS")
		)
		(fp_line
			(start -0.1016 3.655822)
			(end 0.379222 3.655822)
			(stroke
				(width 0.1524)
				(type default)
			)
			(layer "F.SilkS")
		)
		(fp_line
			(start 0.379222 3.655822)
			(end -0.1016 4.488688)
			(stroke
				(width 0.1524)
				(type default)
			)
			(layer "F.SilkS")
		)
		(fp_line
			(start -0.1016 2.744216)
			(end -0.1016 3.655822)
			(stroke
				(width 0.1524)
				(type default)
			)
			(layer "F.SilkS")
		)
		(fp_poly
			(pts
				(xy 0.6223 2.032) (xy -0.6223 2.032) (xy -0.6223 0.0254) (xy 0.6223 0.0254)
			)
			(stroke
				(width 0)
				(type default)
			)
			(fill no)
			(layer "F.CrtYd")
		)
		(fp_line
			(start -0.582422 4.488688)
			(end 0.379222 4.488688)
			(stroke
				(width 0.1)
				(type default)
			)
			(layer "F.Fab")
		)
		(fp_line
			(start -0.1016 4.488688)
			(end -0.1016 5.61213)
			(stroke
				(width 0.1)
				(type default)
			)
			(layer "F.Fab")
		)
		(fp_line
			(start -0.1016 4.488688)
			(end -0.582422 3.655822)
			(stroke
				(width 0.1)
				(type default)
			)
			(layer "F.Fab")
		)
		(fp_line
			(start -0.582422 3.655822)
			(end 0.379222 3.655822)
			(stroke
				(width 0.1)
				(type default)
			)
			(layer "F.Fab")
		)
		(fp_line
			(start -0.1016 3.655822)
			(end -0.1016 2.744216)
			(stroke
				(width 0.1)
				(type default)
			)
			(layer "F.Fab")
		)
		(fp_line
			(start 0.379222 3.655822)
			(end -0.1016 4.488688)
			(stroke
				(width 0.1)
				(type default)
			)
			(layer "F.Fab")
		)
		(fp_line
			(start -0.6223 2.032)
			(end -0.6223 0.0254)
			(stroke
				(width 0.1)
				(type default)
			)
			(layer "F.Fab")
		)
		(fp_line
			(start 0.6223 2.032)
			(end -0.6223 2.032)
			(stroke
				(width 0.1)
				(type default)
			)
			(layer "F.Fab")
		)
		(fp_line
			(start -0.6223 0.0254)
			(end 0.6223 0.0254)
			(stroke
				(width 0.1)
				(type default)
			)
			(layer "F.Fab")
		)
		(fp_line
			(start 0.6223 0.0254)
			(end 0.6223 2.032)
			(stroke
				(width 0.1)
				(type default)
			)
			(layer "F.Fab")
		)
		(pad "1" smd rect
			(at 0 0 270)
			(size 1.27 1.27)
			(layers "F.Cu" "F.Mask" "F.Paste")
			(net "FM_PWR_LED_A")
		)
		(pad "2" smd rect
			(at 0 2.032 270)
			(size 1.27 1.27)
			(layers "F.Cu" "F.Mask" "F.Paste")
			(net "FM_PWR_LED_K")
		)
		(zone
			(layer "F.Cu")
			(hatch none 0.5)
			(connect_pads
				(clearance 0)
			)
			(min_thickness 0.25)
			(keepout
				(tracks not_allowed)
				(vias allowed)
				(pads allowed)
				(copperpour not_allowed)
				(footprints allowed)
			)
			(placement
				(enabled no)
				(sheetname "")
			)
			(fill
				(thermal_gap 0.5)
				(thermal_bridge_width 0.5)
				(island_removal_mode 0)
			)
			(polygon
				(pts
					(xy 478.83064 -137.963402) (xy 478.83064 -136.693402) (xy 479.59264 -136.693402) (xy 479.59264 -137.963402)
				)
			)
		)
		(zone
			(layer "F.Cu")
			(hatch none 0.5)
			(connect_pads
				(clearance 0)
			)
			(min_thickness 0.25)
			(keepout
				(tracks allowed)
				(vias not_allowed)
				(pads allowed)
				(copperpour not_allowed)
				(footprints allowed)
			)
			(placement
				(enabled no)
				(sheetname "")
			)
			(fill
				(thermal_gap 0.5)
				(thermal_bridge_width 0.5)
				(island_removal_mode 0)
			)
			(polygon
				(pts
					(xy 478.83064 -137.963402) (xy 478.83064 -136.693402) (xy 479.59264 -136.693402) (xy 479.59264 -137.963402)
				)
			)
		)
	)
)
